# S9S_MB_2U (Grand Teton) — schematic netlist excerpt (pin names and nets, part order shuffled) for the footprints in the layout excerpt that follows; sources: Cadence DE-HDL packaged netlist, KiCad conversion of 03242023_DA0F0TMBIJ0_F0T_Motherboard_J_brd_V01_OCP.brd

R4192  Q_RES  1K 1% EMPTY  pkg 0402LF  page 170 : A = P3V3_AUX ; B = U273_3_ADD1
PR3852  Q_RES  71.5K 1% EMPTY  pkg 0402LF  page 163 : A = P12V_OCP_V3_2 ; B = P12V_OCP_OV_FB_2

(kicad_pcb
	(version 20260206)
	(generator "pcbnew")
	(generator_version "10.0")
	(general
		(thickness 1.6)
		(legacy_teardrops no)
	)
	(paper "A4")
	(title_block
		(title "03242023_DA0F0TMBIJ0_F0T_Motherboard_J_brd_V01_OCP.brd")
		(comment 1 "Grand Teton / footprints 3760-3761 of 6105")
	)
	(layers
		(0 "F.Cu" signal "TOP")
		(4 "In1.Cu" signal "GND")
		(6 "In2.Cu" signal "IN1")
		(8 "In3.Cu" signal "GND1")
		(10 "In4.Cu" signal "IN2")
		(12 "In5.Cu" signal "GND2")
		(14 "In6.Cu" signal "IN3")
		(16 "In7.Cu" signal "GND3")
		(18 "In8.Cu" signal "VCC")
		(20 "In9.Cu" signal "VCC1")
		(22 "In10.Cu" signal "GND4")
		(24 "In11.Cu" signal "IN4")
		(26 "In12.Cu" signal "GND5")
		(28 "In13.Cu" signal "IN5")
		(30 "In14.Cu" signal "GND6")
		(32 "In15.Cu" signal "IN6")
		(34 "In16.Cu" signal "GND7")
		(2 "B.Cu" signal "BOTTOM")
		(9 "F.Adhes" user "F.Adhesive")
		(11 "B.Adhes" user "B.Adhesive")
		(13 "F.Paste" user "Package Geometry/Pastemask Top")
		(15 "B.Paste" user "Package Geometry/Pastemask Bottom")
		(5 "F.SilkS" user "Ref Des/Silkscreen Top")
		(7 "B.SilkS" user "Ref Des/Silkscreen Bottom")
		(1 "F.Mask" user "Board Geometry/Soldermask Top")
		(3 "B.Mask" user "Board Geometry/Soldermask Bottom")
		(17 "Dwgs.User" user "User.Drawings")
		(19 "Cmts.User" user "User.Comments")
		(21 "Eco1.User" user "User.Eco1")
		(23 "Eco2.User" user "User.Eco2")
		(25 "Edge.Cuts" user "Board Geometry/Outline")
		(27 "Margin" user)
		(31 "F.CrtYd" user "Package Geometry/Place Bound Top")
		(29 "B.CrtYd" user "Package Geometry/Place Bound Bottom")
		(35 "F.Fab" user "Ref Des/Assembly Top")
		(33 "B.Fab" user "Ref Des/Assembly Bottom")
	)
	(footprint ""
		(layer "F.Cu")
		(at 61.845698 -26.99004 90)
		(property "Reference" "PR3852"
			(at 0 0 90)
			(layer "F.SilkS")
			(hide yes)
			(effects
				(font
					(size 1.27 1.27)
				)
			)
		)
		(property "Value" ""
			(at 0 0 90)
			(layer "F.Fab")
			(effects
				(font
					(size 1.27 1.27)
				)
			)
		)
		(duplicate_pad_numbers_are_jumpers no)
		(fp_line
			(start 0.7874 -0.4064)
			(end 0.7874 0.4064)
			(stroke
				(width 0.1524)
				(type default)
			)
			(layer "F.SilkS")
		)
		(fp_line
			(start -0.7874 -0.4064)
			(end 0.7874 -0.4064)
			(stroke
				(width 0.1524)
				(type default)
			)
			(layer "F.SilkS")
		)
		(fp_line
			(start 0.7874 0.4064)
			(end -0.7874 0.4064)
			(stroke
				(width 0.1524)
				(type default)
			)
			(layer "F.SilkS")
		)
		(fp_line
			(start -0.7874 0.4064)
			(end -0.7874 -0.4064)
			(stroke
				(width 0.1524)
				(type default)
			)
			(layer "F.SilkS")
		)
		(fp_line
			(start -0.12065 -0.305054)
			(end -0.12065 -0.2794)
			(stroke
				(width 0.1)
				(type default)
			)
			(layer "F.Fab")
		)
		(fp_line
			(start -0.67945 -0.305054)
			(end -0.12065 -0.305054)
			(stroke
				(width 0.1)
				(type default)
			)
			(layer "F.Fab")
		)
		(fp_line
			(start 0.67945 -0.3048)
			(end 0.67945 0.3048)
			(stroke
				(width 0.1)
				(type default)
			)
			(layer "F.Fab")
		)
		(fp_line
			(start 0.12065 -0.3048)
			(end 0.67945 -0.3048)
			(stroke
				(width 0.1)
				(type default)
			)
			(layer "F.Fab")
		)
		(fp_line
			(start 0.12065 -0.2794)
			(end 0.12065 -0.3048)
			(stroke
				(width 0.1)
				(type default)
			)
			(layer "F.Fab")
		)
		(fp_line
			(start -0.12065 -0.2794)
			(end 0.12065 -0.2794)
			(stroke
				(width 0.1)
				(type default)
			)
			(layer "F.Fab")
		)
		(fp_line
			(start 0.120396 0.2794)
			(end -0.12065 0.2794)
			(stroke
				(width 0.1)
				(type default)
			)
			(layer "F.Fab")
		)
		(fp_line
			(start -0.12065 0.2794)
			(end -0.12065 0.3048)
			(stroke
				(width 0.1)
				(type default)
			)
			(layer "F.Fab")
		)
		(fp_line
			(start 0.67945 0.3048)
			(end 0.120396 0.3048)
			(stroke
				(width 0.1)
				(type default)
			)
			(layer "F.Fab")
		)
		(fp_line
			(start 0.120396 0.3048)
			(end 0.120396 0.2794)
			(stroke
				(width 0.1)
				(type default)
			)
			(layer "F.Fab")
		)
		(fp_line
			(start -0.12065 0.3048)
			(end -0.67945 0.3048)
			(stroke
				(width 0.1)
				(type default)
			)
			(layer "F.Fab")
		)
		(fp_line
			(start -0.67945 0.3048)
			(end -0.67945 -0.305054)
			(stroke
				(width 0.1)
				(type default)
			)
			(layer "F.Fab")
		)
		(pad "1" smd circle
			(at -0.40005 0 90)
			(size 0 0)
			(layers "F.Cu" "F.Mask" "F.Paste")
			(net "P12V_OCP_V3_2")
		)
		(pad "2" smd circle
			(at 0.40005 0 90)
			(size 0 0)
			(layers "F.Cu" "F.Mask" "F.Paste")
			(net "P12V_OCP_OV_FB_2")
		)
	)
	(footprint ""
		(layer "F.Cu")
		(at 123.769882 -15.54607 180)
		(property "Reference" "R4192"
			(at 0 0 180)
			(layer "F.SilkS")
			(hide yes)
			(effects
				(font
					(size 1.27 1.27)
				)
			)
		)
		(property "Value" ""
			(at 0 0 180)
			(layer "F.Fab")
			(effects
				(font
					(size 1.27 1.27)
				)
			)
		)
		(duplicate_pad_numbers_are_jumpers no)
		(fp_line
			(start 0.7874 0.4064)
			(end -0.7874 0.4064)
			(stroke
				(width 0.1524)
				(type default)
			)
			(layer "F.SilkS")
		)
		(fp_line
			(start 0.7874 -0.4064)
			(end 0.7874 0.4064)
			(stroke
				(width 0.1524)
				(type default)
			)
			(layer "F.SilkS")
		)
		(fp_line
			(start -0.7874 0.4064)
			(end -0.7874 -0.4064)
			(stroke
				(width 0.1524)
				(type default)
			)
			(layer "F.SilkS")
		)
		(fp_line
			(start -0.7874 -0.4064)
			(end 0.7874 -0.4064)
			(stroke
				(width 0.1524)
				(type default)
			)
			(layer "F.SilkS")
		)
		(fp_line
			(start 0.67945 0.3048)
			(end 0.120396 0.3048)
			(stroke
				(width 0.1)
				(type default)
			)
			(layer "F.Fab")
		)
		(fp_line
			(start 0.67945 -0.3048)
			(end 0.67945 0.3048)
			(stroke
				(width 0.1)
				(type default)
			)
			(layer "F.Fab")
		)
		(fp_line
			(start 0.12065 -0.2794)
			(end 0.12065 -0.3048)
			(stroke
				(width 0.1)
				(type default)
			)
			(layer "F.Fab")
		)
		(fp_line
			(start 0.12065 -0.3048)
			(end 0.67945 -0.3048)
			(stroke
				(width 0.1)
				(type default)
			)
			(layer "F.Fab")
		)
		(fp_line
			(start 0.120396 0.3048)
			(end 0.120396 0.2794)
			(stroke
				(width 0.1)
				(type default)
			)
			(layer "F.Fab")
		)
		(fp_line
			(start 0.120396 0.2794)
			(end -0.12065 0.2794)
			(stroke
				(width 0.1)
				(type default)
			)
			(layer "F.Fab")
		)
		(fp_line
			(start -0.12065 0.3048)
			(end -0.67945 0.3048)
			(stroke
				(width 0.1)
				(type default)
			)
			(layer "F.Fab")
		)
		(fp_line
			(start -0.12065 0.2794)
			(end -0.12065 0.3048)
			(stroke
				(width 0.1)
				(type default)
			)
			(layer "F.Fab")
		)
		(fp_line
			(start -0.12065 -0.2794)
			(end 0.12065 -0.2794)
			(stroke
				(width 0.1)
				(type default)
			)
			(layer "F.Fab")
		)
		(fp_line
			(start -0.12065 -0.305054)
			(end -0.12065 -0.2794)
			(stroke
				(width 0.1)
				(type default)
			)
			(layer "F.Fab")
		)
		(fp_line
			(start -0.67945 0.3048)
			(end -0.67945 -0.305054)
			(stroke
				(width 0.1)
				(type default)
			)
			(layer "F.Fab")
		)
		(fp_line
			(start -0.67945 -0.305054)
			(end -0.12065 -0.305054)
			(stroke
				(width 0.1)
				(type default)
			)
			(layer "F.Fab")
		)
		(pad "1" smd circle
			(at -0.40005 0 180)
			(size 0 0)
			(layers "F.Cu" "F.Mask" "F.Paste")
			(net "P3V3_AUX")
		)
		(pad "2" smd circle
			(at 0.40005 0 180)
			(size 0 0)
			(layers "F.Cu" "F.Mask" "F.Paste")
			(net "U273_3_ADD1")
		)
	)
)
